(kicad_pcb
	(version 20260206)
	(generator "pcbnew")
	(generator_version "10.0")
	(general
		(thickness 1.6)
		(legacy_teardrops no)
	)
	(paper "A4")
	(title_block
		(title "Bryce Canyon_IOM_IOC_16318-2_OCP.brd")
		(comment 1 "Bryce Canyon / footprints 644-650 of 1605")
	)
	(layers
		(0 "F.Cu" signal "TOP")
		(4 "In1.Cu" signal "L2GND")
		(6 "In2.Cu" signal "L3")
		(8 "In3.Cu" signal "L4VCC")
		(10 "In4.Cu" signal "L5VCC")
		(12 "In5.Cu" signal "L6")
		(14 "In6.Cu" signal "L7GND")
		(2 "B.Cu" signal "BOTTOM")
		(9 "F.Adhes" user "F.Adhesive")
		(11 "B.Adhes" user "B.Adhesive")
		(13 "F.Paste" user "Package Geometry/Pastemask Top")
		(15 "B.Paste" user "Package Geometry/Pastemask Bottom")
		(5 "F.SilkS" user "Ref Des/Silkscreen Top")
		(7 "B.SilkS" user "Ref Des/Silkscreen Bottom")
		(1 "F.Mask" user "Board Geometry/Soldermask Top")
		(3 "B.Mask" user "Board Geometry/Soldermask Bottom")
		(17 "Dwgs.User" user "User.Drawings")
		(19 "Cmts.User" user "User.Comments")
		(21 "Eco1.User" user "User.Eco1")
		(23 "Eco2.User" user "User.Eco2")
		(25 "Edge.Cuts" user "Board Geometry/Outline")
		(27 "Margin" user)
		(31 "F.CrtYd" user "Package Geometry/Place Bound Top")
		(29 "B.CrtYd" user "Package Geometry/Place Bound Bottom")
		(35 "F.Fab" user "Ref Des/Assembly Top")
		(33 "B.Fab" user "Ref Des/Assembly Bottom")
	)
	(footprint ""
		(layer "F.Cu")
		(at 90.424 -29.6418 90)
		(property "Reference" "U98"
			(at 0 0 90)
			(layer "F.SilkS")
			(hide yes)
			(effects
				(font
					(size 1.27 1.27)
				)
			)
		)
		(property "Value" "TPS2065DBVT-GP"
			(at 0 -5.1308 90)
			(unlocked yes)
			(layer "F.Fab")
			(hide yes)
			(effects
				(font
					(size 1.016 1.016)
					(thickness 0.1524)
				)
			)
		)
		(property "Device Type" "SOT-23-5H58"
			(at 0 -6.7564 90)
			(unlocked yes)
			(layer "F.Fab")
			(hide yes)
			(effects
				(font
					(size 1.016 1.016)
					(thickness 0.1524)
				)
			)
		)
		(duplicate_pad_numbers_are_jumpers no)
		(fp_line
			(start 1.778 -2.286)
			(end -1.778 -2.286)
			(stroke
				(width 0.1524)
				(type default)
			)
			(layer "F.SilkS")
		)
		(fp_line
			(start -1.778 -2.286)
			(end -1.778 2.286)
			(stroke
				(width 0.1524)
				(type default)
			)
			(layer "F.SilkS")
		)
		(fp_line
			(start -0.7112 2.2352)
			(end -1.7272 2.2352)
			(stroke
				(width 0.3302)
				(type default)
			)
			(layer "F.SilkS")
		)
		(fp_line
			(start -1.7272 2.2352)
			(end -1.7272 0.762)
			(stroke
				(width 0.3302)
				(type default)
			)
			(layer "F.SilkS")
		)
		(fp_line
			(start 1.778 2.286)
			(end 1.778 -2.286)
			(stroke
				(width 0.1524)
				(type default)
			)
			(layer "F.SilkS")
		)
		(fp_line
			(start -0.254 2.286)
			(end 1.778 2.286)
			(stroke
				(width 0.1524)
				(type default)
			)
			(layer "F.SilkS")
		)
		(fp_line
			(start -1.778 2.286)
			(end 1.778 2.286)
			(stroke
				(width 0.1524)
				(type default)
			)
			(layer "F.SilkS")
		)
		(fp_line
			(start -1.778 2.286)
			(end -0.254 2.286)
			(stroke
				(width 0.1524)
				(type default)
			)
			(layer "F.SilkS")
		)
		(fp_poly
			(pts
				(xy -0.9652 2.4384) (xy -1.3208 2.794) (xy -0.6096 2.794)
			)
			(stroke
				(width 0)
				(type default)
			)
			(fill yes)
			(layer "F.SilkS")
		)
		(fp_rect
			(start -1.778 2.286)
			(end 1.778 -2.286)
			(stroke
				(width 0)
				(type default)
			)
			(fill no)
			(layer "F.CrtYd")
		)
		(fp_rect
			(start -1.778 2.286)
			(end 1.778 -2.286)
			(stroke
				(width 0)
				(type default)
			)
			(fill no)
			(layer "F.Fab")
		)
		(pad "1" smd rect
			(at -0.94996 1.143 90)
			(size 0.508 1.524)
			(layers "F.Cu" "F.Mask" "F.Paste")
			(net "P5V_USB")
		)
		(pad "2" smd rect
			(at 0 1.143 90)
			(size 0.508 1.524)
			(layers "F.Cu" "F.Mask" "F.Paste")
			(net "GND")
		)
		(pad "3" smd rect
			(at 0.94996 1.143 90)
			(size 0.508 1.524)
			(layers "F.Cu" "F.Mask" "F.Paste")
			(net "USB_OCS_N1")
		)
		(pad "4" smd rect
			(at 0.94996 -1.143 90)
			(size 0.508 1.524)
			(layers "F.Cu" "F.Mask" "F.Paste")
			(net "USB_EN_1")
		)
		(pad "5" smd rect
			(at -0.94996 -1.143 90)
			(size 0.508 1.524)
			(layers "F.Cu" "F.Mask" "F.Paste")
			(net "P5V_STBY")
		)
	)
	(footprint ""
		(layer "F.Cu")
		(at 193.4972 -114.321336)
		(property "Reference" "L12"
			(at 0 0 0)
			(layer "F.SilkS")
			(hide yes)
			(effects
				(font
					(size 1.27 1.27)
				)
			)
		)
		(property "Value" "COIL-D24UH-GP"
			(at -5.5118 1.5748 0)
			(unlocked yes)
			(layer "F.Fab")
			(hide yes)
			(effects
				(font
					(size 1.016 1.016)
					(thickness 0.1524)
				)
			)
		)
		(property "Device Type" "L7267-1630H158"
			(at -5.5118 0.0508 0)
			(unlocked yes)
			(layer "F.Fab")
			(hide yes)
			(effects
				(font
					(size 1.016 1.016)
					(thickness 0.1524)
				)
			)
		)
		(duplicate_pad_numbers_are_jumpers no)
		(fp_line
			(start -3.6068 -4.6101)
			(end 3.6068 -4.6101)
			(stroke
				(width 0.1524)
				(type default)
			)
			(layer "F.SilkS")
		)
		(fp_line
			(start -3.6068 4.6101)
			(end -3.6068 -4.6101)
			(stroke
				(width 0.1524)
				(type default)
			)
			(layer "F.SilkS")
		)
		(fp_line
			(start 3.6068 -4.6101)
			(end 3.6068 4.6101)
			(stroke
				(width 0.1524)
				(type default)
			)
			(layer "F.SilkS")
		)
		(fp_line
			(start 3.6068 4.6101)
			(end -3.6068 4.6101)
			(stroke
				(width 0.1524)
				(type default)
			)
			(layer "F.SilkS")
		)
		(fp_rect
			(start -3.3528 3.5941)
			(end 3.3528 -3.5941)
			(stroke
				(width 0)
				(type default)
			)
			(fill no)
			(layer "F.CrtYd")
		)
		(fp_poly
			(pts
				(xy -3.8608 4.6863) (xy -3.8608 3.5941) (xy 3.3528 3.5941) (xy 3.3528 -3.5941) (xy -3.3528 -3.5941)
				(xy -3.3528 3.5814) (xy -3.8608 3.5814) (xy -3.8608 -4.6863) (xy 3.8608 -4.6863) (xy 3.8608 4.6863)
			)
			(stroke
				(width 0)
				(type default)
			)
			(fill no)
			(layer "F.CrtYd")
		)
		(fp_rect
			(start -3.8608 4.6863)
			(end 3.8608 -4.6863)
			(stroke
				(width 0)
				(type default)
			)
			(fill no)
			(layer "F.Fab")
		)
		(pad "1" smd rect
			(at 0 -2.990596)
			(size 3.5052 2.7432)
			(layers "F.Cu" "F.Mask" "F.Paste")
			(net "VT235_VX")
		)
		(pad "2" smd rect
			(at 0 2.990596)
			(size 3.5052 2.7432)
			(layers "F.Cu" "F.Mask" "F.Paste")
			(net "P0V975")
		)
	)
	(footprint ""
		(layer "F.Cu")
		(at 183.4261 -48.1457)
		(property "Reference" "R668"
			(at 0 0 0)
			(layer "F.SilkS")
			(hide yes)
			(effects
				(font
					(size 1.27 1.27)
				)
			)
		)
		(property "Value" "10KR2F-2-GP"
			(at 0.064008 -3.993896 0)
			(unlocked yes)
			(layer "F.Fab")
			(hide yes)
			(effects
				(font
					(size 1.016 1.016)
					(thickness 0.1524)
				)
			)
		)
		(property "Device Type" "R402H16"
			(at 0.064008 -5.517896 0)
			(unlocked yes)
			(layer "F.Fab")
			(hide yes)
			(effects
				(font
					(size 1.016 1.016)
					(thickness 0.1524)
				)
			)
		)
		(duplicate_pad_numbers_are_jumpers no)
		(fp_line
			(start -0.508 -0.9398)
			(end -0.508 0.9398)
			(stroke
				(width 0.1524)
				(type default)
			)
			(layer "F.SilkS")
		)
		(fp_line
			(start 0.508 -0.9398)
			(end -0.508 -0.9398)
			(stroke
				(width 0.1524)
				(type default)
			)
			(layer "F.SilkS")
		)
		(fp_rect
			(start -0.508 0.9398)
			(end 0.508 -0.9398)
			(stroke
				(width 0)
				(type default)
			)
			(fill no)
			(layer "F.CrtYd")
		)
		(fp_rect
			(start -0.508 0.9398)
			(end 0.508 -0.9398)
			(stroke
				(width 0)
				(type default)
			)
			(fill no)
			(layer "F.Fab")
		)
		(pad "1" smd custom
			(at 0 -0.4445)
			(size 0.1397 0.1397)
			(layers "F.Cu" "F.Mask" "F.Paste")
			(net "XM_ADDR_1")
			(options
				(clearance outline)
				(anchor circle)
			)
			(primitives
				(gr_poly
					(pts
						(arc
							(start -0.1778 -0.2794)
							(mid -0.249642 -0.249642)
							(end -0.2794 -0.1778)
						)
						(arc
							(start -0.2794 0.1778)
							(mid -0.249642 0.249642)
							(end -0.1778 0.2794)
						)
						(arc
							(start 0.1778 0.2794)
							(mid 0.249642 0.249642)
							(end 0.2794 0.1778)
						)
						(arc
							(start 0.2794 -0.1778)
							(mid 0.249642 -0.249642)
							(end 0.1778 -0.2794)
						)
					)
					(width 0)
					(fill yes)
				)
			)
		)
		(pad "2" smd custom
			(at 0 0.4445)
			(size 0.1397 0.1397)
			(layers "F.Cu" "F.Mask" "F.Paste")
			(net "GND")
			(options
				(clearance outline)
				(anchor circle)
			)
			(primitives
				(gr_poly
					(pts
						(arc
							(start -0.1778 -0.2794)
							(mid -0.249642 -0.249642)
							(end -0.2794 -0.1778)
						)
						(arc
							(start -0.2794 0.1778)
							(mid -0.249642 0.249642)
							(end -0.1778 0.2794)
						)
						(arc
							(start 0.1778 0.2794)
							(mid 0.249642 0.249642)
							(end 0.2794 0.1778)
						)
						(arc
							(start 0.2794 -0.1778)
							(mid 0.249642 -0.249642)
							(end 0.1778 -0.2794)
						)
					)
					(width 0)
					(fill yes)
				)
			)
		)
	)
	(footprint ""
		(layer "F.Cu")
		(at 70.104 -146.05 90)
		(property "Reference" "R763"
			(at 0 0 90)
			(layer "F.SilkS")
			(hide yes)
			(effects
				(font
					(size 1.27 1.27)
				)
			)
		)
		(property "Value" "33R2J-2-GP"
			(at 0.064008 -3.993896 90)
			(unlocked yes)
			(layer "F.Fab")
			(hide yes)
			(effects
				(font
					(size 1.016 1.016)
					(thickness 0.1524)
				)
			)
		)
		(property "Device Type" "R402H16"
			(at 0.064008 -5.517896 90)
			(unlocked yes)
			(layer "F.Fab")
			(hide yes)
			(effects
				(font
					(size 1.016 1.016)
					(thickness 0.1524)
				)
			)
		)
		(duplicate_pad_numbers_are_jumpers no)
		(fp_line
			(start 0.508 -0.9398)
			(end -0.508 -0.9398)
			(stroke
				(width 0.1524)
				(type default)
			)
			(layer "F.SilkS")
		)
		(fp_line
			(start -0.508 -0.9398)
			(end -0.508 0.9398)
			(stroke
				(width 0.1524)
				(type default)
			)
			(layer "F.SilkS")
		)
		(fp_rect
			(start -0.508 0.9398)
			(end 0.508 -0.9398)
			(stroke
				(width 0)
				(type default)
			)
			(fill no)
			(layer "F.CrtYd")
		)
		(fp_rect
			(start -0.508 0.9398)
			(end 0.508 -0.9398)
			(stroke
				(width 0)
				(type default)
			)
			(fill no)
			(layer "F.Fab")
		)
		(pad "1" smd custom
			(at 0 -0.4445 90)
			(size 0.1397 0.1397)
			(layers "F.Cu" "F.Mask" "F.Paste")
			(net "NCSI_RCLK_R")
			(options
				(clearance outline)
				(anchor circle)
			)
			(primitives
				(gr_poly
					(pts
						(arc
							(start -0.1778 -0.2794)
							(mid -0.249642 -0.249642)
							(end -0.2794 -0.1778)
						)
						(arc
							(start -0.2794 0.1778)
							(mid -0.249642 0.249642)
							(end -0.1778 0.2794)
						)
						(arc
							(start 0.1778 0.2794)
							(mid 0.249642 0.249642)
							(end 0.2794 0.1778)
						)
						(arc
							(start 0.2794 -0.1778)
							(mid 0.249642 -0.249642)
							(end 0.1778 -0.2794)
						)
					)
					(width 0)
					(fill yes)
				)
			)
		)
		(pad "2" smd custom
			(at 0 0.4445 90)
			(size 0.1397 0.1397)
			(layers "F.Cu" "F.Mask" "F.Paste")
			(net "NCSI_RCLK")
			(options
				(clearance outline)
				(anchor circle)
			)
			(primitives
				(gr_poly
					(pts
						(arc
							(start -0.1778 -0.2794)
							(mid -0.249642 -0.249642)
							(end -0.2794 -0.1778)
						)
						(arc
							(start -0.2794 0.1778)
							(mid -0.249642 0.249642)
							(end -0.1778 0.2794)
						)
						(arc
							(start 0.1778 0.2794)
							(mid 0.249642 0.249642)
							(end 0.2794 0.1778)
						)
						(arc
							(start 0.2794 -0.1778)
							(mid 0.249642 -0.249642)
							(end 0.1778 -0.2794)
						)
					)
					(width 0)
					(fill yes)
				)
			)
		)
	)
	(footprint ""
		(layer "F.Cu")
		(at 199.8345 -22.8092)
		(property "Reference" "Q24"
			(at 0 0 0)
			(layer "F.SilkS")
			(hide yes)
			(effects
				(font
					(size 1.27 1.27)
				)
			)
		)
		(property "Value" "SSM3K324R-GP"
			(at 0.127 -8.9662 0)
			(unlocked yes)
			(layer "F.Fab")
			(hide yes)
			(effects
				(font
					(size 1.016 1.016)
					(thickness 0.1524)
				)
			)
		)
		(property "Device Type" "SOT23DGS2D4H35"
			(at 0.127 -10.4902 0)
			(unlocked yes)
			(layer "F.Fab")
			(hide yes)
			(effects
				(font
					(size 1.016 1.016)
					(thickness 0.1524)
				)
			)
		)
		(duplicate_pad_numbers_are_jumpers no)
		(fp_line
			(start -1.651 -1.778)
			(end -1.651 1.778)
			(stroke
				(width 0.1524)
				(type default)
			)
			(layer "F.SilkS")
		)
		(fp_line
			(start -1.651 1.778)
			(end 1.651 1.778)
			(stroke
				(width 0.1524)
				(type default)
			)
			(layer "F.SilkS")
		)
		(fp_line
			(start 1.651 -1.778)
			(end -1.651 -1.778)
			(stroke
				(width 0.1524)
				(type default)
			)
			(layer "F.SilkS")
		)
		(fp_line
			(start 1.651 1.778)
			(end 1.651 -1.778)
			(stroke
				(width 0.1524)
				(type default)
			)
			(layer "F.SilkS")
		)
		(fp_poly
			(pts
				(xy -1.778 1.8796) (xy -1.778 -1.8796) (xy 1.778 -1.8796) (xy 1.778 1.8796)
			)
			(stroke
				(width 0)
				(type default)
			)
			(fill no)
			(layer "F.CrtYd")
		)
		(fp_poly
			(pts
				(xy -1.778 1.8796) (xy -1.778 -1.8796) (xy 1.778 -1.8796) (xy 1.778 1.8796)
			)
			(stroke
				(width 0)
				(type default)
			)
			(fill no)
			(layer "F.Fab")
		)
		(pad "D" smd custom
			(at 0 -0.9525)
			(size 0.1905 0.1905)
			(layers "F.Cu" "F.Mask" "F.Paste")
			(net "EXT1_LED_BLUE_G2")
			(options
				(clearance outline)
				(anchor circle)
			)
			(primitives
				(gr_poly
					(pts
						(arc
							(start -0.1778 0.5715)
							(mid -0.321484 0.511984)
							(end -0.381 0.3683)
						)
						(arc
							(start -0.381 -0.3683)
							(mid -0.321484 -0.511984)
							(end -0.1778 -0.5715)
						)
						(arc
							(start 0.1778 -0.5715)
							(mid 0.321484 -0.511984)
							(end 0.381 -0.3683)
						)
						(arc
							(start 0.381 0.3683)
							(mid 0.321484 0.511984)
							(end 0.1778 0.5715)
						)
					)
					(width 0)
					(fill yes)
				)
			)
		)
		(pad "G" smd custom
			(at -0.98425 0.9525)
			(size 0.1905 0.1905)
			(layers "F.Cu" "F.Mask" "F.Paste")
			(net "EXT1_LED_BLUE_G_Q24")
			(options
				(clearance outline)
				(anchor circle)
			)
			(primitives
				(gr_poly
					(pts
						(arc
							(start -0.1778 0.5715)
							(mid -0.321484 0.511984)
							(end -0.381 0.3683)
						)
						(arc
							(start -0.381 -0.3683)
							(mid -0.321484 -0.511984)
							(end -0.1778 -0.5715)
						)
						(arc
							(start 0.1778 -0.5715)
							(mid 0.321484 -0.511984)
							(end 0.381 -0.3683)
						)
						(arc
							(start 0.381 0.3683)
							(mid 0.321484 0.511984)
							(end 0.1778 0.5715)
						)
					)
					(width 0)
					(fill yes)
				)
			)
		)
		(pad "S" smd custom
			(at 0.98425 0.9525)
			(size 0.1905 0.1905)
			(layers "F.Cu" "F.Mask" "F.Paste")
			(net "GND")
			(options
				(clearance outline)
				(anchor circle)
			)
			(primitives
				(gr_poly
					(pts
						(arc
							(start -0.1778 0.5715)
							(mid -0.321484 0.511984)
							(end -0.381 0.3683)
						)
						(arc
							(start -0.381 -0.3683)
							(mid -0.321484 -0.511984)
							(end -0.1778 -0.5715)
						)
						(arc
							(start 0.1778 -0.5715)
							(mid 0.321484 -0.511984)
							(end 0.381 -0.3683)
						)
						(arc
							(start 0.381 0.3683)
							(mid 0.321484 0.511984)
							(end 0.1778 0.5715)
						)
					)
					(width 0)
					(fill yes)
				)
			)
		)
	)
	(footprint ""
		(layer "F.Cu")
		(at 188.4172 -127.3302 -90)
		(property "Reference" "R564"
			(at 0 0 270)
			(layer "F.SilkS")
			(hide yes)
			(effects
				(font
					(size 1.27 1.27)
				)
			)
		)
		(property "Value" "7K32R2F-GP"
			(at 0.064008 -3.993896 270)
			(unlocked yes)
			(layer "F.Fab")
			(hide yes)
			(effects
				(font
					(size 1.016 1.016)
					(thickness 0.1524)
				)
			)
		)
		(property "Device Type" "R402H16"
			(at 0.064008 -5.517896 270)
			(unlocked yes)
			(layer "F.Fab")
			(hide yes)
			(effects
				(font
					(size 1.016 1.016)
					(thickness 0.1524)
				)
			)
		)
		(duplicate_pad_numbers_are_jumpers no)
		(fp_line
			(start -0.508 -0.9398)
			(end -0.508 0.9398)
			(stroke
				(width 0.1524)
				(type default)
			)
			(layer "F.SilkS")
		)
		(fp_line
			(start 0.508 -0.9398)
			(end -0.508 -0.9398)
			(stroke
				(width 0.1524)
				(type default)
			)
			(layer "F.SilkS")
		)
		(fp_rect
			(start -0.508 0.9398)
			(end 0.508 -0.9398)
			(stroke
				(width 0)
				(type default)
			)
			(fill no)
			(layer "F.CrtYd")
		)
		(fp_rect
			(start -0.508 0.9398)
			(end 0.508 -0.9398)
			(stroke
				(width 0)
				(type default)
			)
			(fill no)
			(layer "F.Fab")
		)
		(pad "1" smd custom
			(at 0 -0.4445 270)
			(size 0.1397 0.1397)
			(layers "F.Cu" "F.Mask" "F.Paste")
			(net "VT235_VREF")
			(options
				(clearance outline)
				(anchor circle)
			)
			(primitives
				(gr_poly
					(pts
						(arc
							(start -0.1778 -0.2794)
							(mid -0.249642 -0.249642)
							(end -0.2794 -0.1778)
						)
						(arc
							(start -0.2794 0.1778)
							(mid -0.249642 0.249642)
							(end -0.1778 0.2794)
						)
						(arc
							(start 0.1778 0.2794)
							(mid 0.249642 0.249642)
							(end 0.2794 0.1778)
						)
						(arc
							(start 0.2794 -0.1778)
							(mid 0.249642 -0.249642)
							(end 0.1778 -0.2794)
						)
					)
					(width 0)
					(fill yes)
				)
			)
		)
		(pad "2" smd custom
			(at 0 0.4445 270)
			(size 0.1397 0.1397)
			(layers "F.Cu" "F.Mask" "F.Paste")
			(net "VT235_VDES_RR")
			(options
				(clearance outline)
				(anchor circle)
			)
			(primitives
				(gr_poly
					(pts
						(arc
							(start -0.1778 -0.2794)
							(mid -0.249642 -0.249642)
							(end -0.2794 -0.1778)
						)
						(arc
							(start -0.2794 0.1778)
							(mid -0.249642 0.249642)
							(end -0.1778 0.2794)
						)
						(arc
							(start 0.1778 0.2794)
							(mid 0.249642 0.249642)
							(end 0.2794 0.1778)
						)
						(arc
							(start 0.2794 -0.1778)
							(mid 0.249642 -0.249642)
							(end 0.1778 -0.2794)
						)
					)
					(width 0)
					(fill yes)
				)
			)
		)
	)
	(footprint ""
		(layer "F.Cu")
		(at 195.51777 -10.09269 90)
		(property "Reference" "R733"
			(at 0 0 90)
			(layer "F.SilkS")
			(hide yes)
			(effects
				(font
					(size 1.27 1.27)
				)
			)
		)
		(property "Value" "120R3F-L-GP"
			(at -0.0254 -2.5146 90)
			(unlocked yes)
			(layer "F.Fab")
			(hide yes)
			(effects
				(font
					(size 1.016 1.016)
					(thickness 0.1524)
				)
			)
		)
		(property "Device Type" "R603H22"
			(at -0.0254 -4.0386 90)
			(unlocked yes)
			(layer "F.Fab")
			(hide yes)
			(effects
				(font
					(size 1.016 1.016)
					(thickness 0.1524)
				)
			)
		)
		(duplicate_pad_numbers_are_jumpers no)
		(fp_line
			(start 0.2032 0)
			(end 0.4826 0)
			(stroke
				(width 0.2032)
				(type default)
			)
			(layer "F.SilkS")
		)
		(fp_line
			(start -0.4826 0)
			(end -0.2032 0)
			(stroke
				(width 0.2032)
				(type default)
			)
			(layer "F.SilkS")
		)
		(fp_rect
			(start -0.5842 1.3335)
			(end 0.5842 -1.3335)
			(stroke
				(width 0)
				(type default)
			)
			(fill no)
			(layer "F.CrtYd")
		)
		(fp_rect
			(start -0.5842 1.3335)
			(end 0.5842 -1.3335)
			(stroke
				(width 0)
				(type default)
			)
			(fill no)
			(layer "F.Fab")
		)
		(pad "1" smd custom
			(at 0 -0.762 90)
			(size 0.2159 0.2159)
			(layers "F.Cu" "F.Mask" "F.Paste")
			(net "EXT1_LED_YELLOW_D1")
			(options
				(clearance outline)
				(anchor circle)
			)
			(primitives
				(gr_poly
					(pts
						(arc
							(start -0.3302 -0.4318)
							(mid -0.402042 -0.402042)
							(end -0.4318 -0.3302)
						)
						(arc
							(start -0.4318 0.3302)
							(mid -0.402042 0.402042)
							(end -0.3302 0.4318)
						)
						(arc
							(start 0.3302 0.4318)
							(mid 0.402042 0.402042)
							(end 0.4318 0.3302)
						)
						(arc
							(start 0.4318 -0.3302)
							(mid 0.402042 -0.402042)
							(end 0.3302 -0.4318)
						)
					)
					(width 0)
					(fill yes)
				)
			)
		)
		(pad "2" smd custom
			(at 0 0.762 90)
			(size 0.2159 0.2159)
			(layers "F.Cu" "F.Mask" "F.Paste")
			(net "EXT1_LED_YELLOW")
			(options
				(clearance outline)
				(anchor circle)
			)
			(primitives
				(gr_poly
					(pts
						(arc
							(start -0.3302 -0.4318)
							(mid -0.402042 -0.402042)
							(end -0.4318 -0.3302)
						)
						(arc
							(start -0.4318 0.3302)
							(mid -0.402042 0.402042)
							(end -0.3302 0.4318)
						)
						(arc
							(start 0.3302 0.4318)
							(mid 0.402042 0.402042)
							(end 0.4318 0.3302)
						)
						(arc
							(start 0.4318 -0.3302)
							(mid 0.402042 -0.402042)
							(end 0.3302 -0.4318)
						)
					)
					(width 0)
					(fill yes)
				)
			)
		)
	)
)
